# T6G (Grand Teton) — schematic netlist excerpt (pin names and nets, part order shuffled) for the footprints in the layout excerpt that follows; sources: Cadence DE-HDL packaged netlist, KiCad conversion of 04192023_DAF0TMB3IC0_F0TG_MB_C_brd_V02_OCP.brd

PC2206  Q_CAP  0.1UF 25V 10% X7R  pkg 0402  page 147 : A = P12V_E1S_0 ; B = GND
PC19  Q_CAP  0.22UF 16V 10% X7R  pkg 0402  page 226 : A = SW_PVDD18_S5_P1_BST_R ; B = SW_PVDD18_S5_P1_SW

(kicad_pcb
	(version 20260206)
	(generator "pcbnew")
	(generator_version "10.0")
	(general
		(thickness 1.6)
		(legacy_teardrops no)
	)
	(paper "A4")
	(title_block
		(title "04192023_DAF0TMB3IC0_F0TG_MB_C_brd_V02_OCP.brd")
		(comment 1 "Grand Teton / footprints 2683-2684 of 8354")
	)
	(layers
		(0 "F.Cu" signal "TOP")
		(4 "In1.Cu" signal "GND")
		(6 "In2.Cu" signal "IN1")
		(8 "In3.Cu" signal "GND1")
		(10 "In4.Cu" signal "IN2")
		(12 "In5.Cu" signal "GND2")
		(14 "In6.Cu" signal "IN3")
		(16 "In7.Cu" signal "GND3")
		(18 "In8.Cu" signal "VCC")
		(20 "In9.Cu" signal "VCC1")
		(22 "In10.Cu" signal "GND4")
		(24 "In11.Cu" signal "IN4")
		(26 "In12.Cu" signal "GND5")
		(28 "In13.Cu" signal "IN5")
		(30 "In14.Cu" signal "GND6")
		(32 "In15.Cu" signal "IN6")
		(34 "In16.Cu" signal "GND7")
		(2 "B.Cu" signal "BOTTOM")
		(9 "F.Adhes" user "F.Adhesive")
		(11 "B.Adhes" user "B.Adhesive")
		(13 "F.Paste" user "Package Geometry/Pastemask Top")
		(15 "B.Paste" user "Package Geometry/Pastemask Bottom")
		(5 "F.SilkS" user "Ref Des/Silkscreen Top")
		(7 "B.SilkS" user "Ref Des/Silkscreen Bottom")
		(1 "F.Mask" user "Board Geometry/Soldermask Top")
		(3 "B.Mask" user "Board Geometry/Soldermask Bottom")
		(17 "Dwgs.User" user "User.Drawings")
		(19 "Cmts.User" user "User.Comments")
		(21 "Eco1.User" user "User.Eco1")
		(23 "Eco2.User" user "User.Eco2")
		(25 "Edge.Cuts" user "Board Geometry/Outline")
		(27 "Margin" user)
		(31 "F.CrtYd" user "Package Geometry/Place Bound Top")
		(29 "B.CrtYd" user "Package Geometry/Place Bound Bottom")
		(35 "F.Fab" user "Ref Des/Assembly Top")
		(33 "B.Fab" user "Ref Des/Assembly Bottom")
	)
	(footprint ""
		(layer "F.Cu")
		(at 66.635122 -148.335746 180)
		(property "Reference" "PC19"
			(at 0 0 180)
			(layer "F.SilkS")
			(hide yes)
			(effects
				(font
					(size 1.27 1.27)
				)
			)
		)
		(property "Value" ""
			(at 0 0 180)
			(layer "F.Fab")
			(effects
				(font
					(size 1.27 1.27)
				)
			)
		)
		(duplicate_pad_numbers_are_jumpers no)
		(fp_line
			(start 0.7874 0.4064)
			(end -0.7874 0.4064)
			(stroke
				(width 0.1524)
				(type default)
			)
			(layer "F.SilkS")
		)
		(fp_line
			(start 0.7874 -0.4064)
			(end 0.7874 0.4064)
			(stroke
				(width 0.1524)
				(type default)
			)
			(layer "F.SilkS")
		)
		(fp_line
			(start -0.7874 0.4064)
			(end -0.7874 -0.4064)
			(stroke
				(width 0.1524)
				(type default)
			)
			(layer "F.SilkS")
		)
		(fp_line
			(start -0.7874 -0.4064)
			(end 0.7874 -0.4064)
			(stroke
				(width 0.1524)
				(type default)
			)
			(layer "F.SilkS")
		)
		(fp_line
			(start 0.67945 0.3048)
			(end 0.120396 0.3048)
			(stroke
				(width 0.1)
				(type default)
			)
			(layer "F.Fab")
		)
		(fp_line
			(start 0.67945 -0.3048)
			(end 0.67945 0.3048)
			(stroke
				(width 0.1)
				(type default)
			)
			(layer "F.Fab")
		)
		(fp_line
			(start 0.12065 -0.2794)
			(end 0.12065 -0.3048)
			(stroke
				(width 0.1)
				(type default)
			)
			(layer "F.Fab")
		)
		(fp_line
			(start 0.12065 -0.3048)
			(end 0.67945 -0.3048)
			(stroke
				(width 0.1)
				(type default)
			)
			(layer "F.Fab")
		)
		(fp_line
			(start 0.120396 0.3048)
			(end 0.120396 0.2794)
			(stroke
				(width 0.1)
				(type default)
			)
			(layer "F.Fab")
		)
		(fp_line
			(start 0.120396 0.2794)
			(end -0.12065 0.2794)
			(stroke
				(width 0.1)
				(type default)
			)
			(layer "F.Fab")
		)
		(fp_line
			(start -0.12065 0.3048)
			(end -0.67945 0.3048)
			(stroke
				(width 0.1)
				(type default)
			)
			(layer "F.Fab")
		)
		(fp_line
			(start -0.12065 0.2794)
			(end -0.12065 0.3048)
			(stroke
				(width 0.1)
				(type default)
			)
			(layer "F.Fab")
		)
		(fp_line
			(start -0.12065 -0.2794)
			(end 0.12065 -0.2794)
			(stroke
				(width 0.1)
				(type default)
			)
			(layer "F.Fab")
		)
		(fp_line
			(start -0.12065 -0.305054)
			(end -0.12065 -0.2794)
			(stroke
				(width 0.1)
				(type default)
			)
			(layer "F.Fab")
		)
		(fp_line
			(start -0.67945 0.3048)
			(end -0.67945 -0.305054)
			(stroke
				(width 0.1)
				(type default)
			)
			(layer "F.Fab")
		)
		(fp_line
			(start -0.67945 -0.305054)
			(end -0.12065 -0.305054)
			(stroke
				(width 0.1)
				(type default)
			)
			(layer "F.Fab")
		)
		(pad "1" smd circle
			(at -0.40005 0 180)
			(size 0 0)
			(layers "F.Cu" "F.Mask" "F.Paste")
			(net "SW_PVDD18_S5_P1_BST_R")
		)
		(pad "2" smd circle
			(at 0.40005 0 180)
			(size 0 0)
			(layers "F.Cu" "F.Mask" "F.Paste")
			(net "SW_PVDD18_S5_P1_SW")
		)
	)
	(footprint ""
		(layer "F.Cu")
		(at 251.16409 -49.137062 -90)
		(property "Reference" "PC2206"
			(at 0 0 270)
			(layer "F.SilkS")
			(hide yes)
			(effects
				(font
					(size 1.27 1.27)
				)
			)
		)
		(property "Value" ""
			(at 0 0 270)
			(layer "F.Fab")
			(effects
				(font
					(size 1.27 1.27)
				)
			)
		)
		(duplicate_pad_numbers_are_jumpers no)
		(fp_line
			(start -0.7874 0.4064)
			(end -0.7874 -0.4064)
			(stroke
				(width 0.1524)
				(type default)
			)
			(layer "F.SilkS")
		)
		(fp_line
			(start 0.7874 0.4064)
			(end -0.7874 0.4064)
			(stroke
				(width 0.1524)
				(type default)
			)
			(layer "F.SilkS")
		)
		(fp_line
			(start -0.7874 -0.4064)
			(end 0.7874 -0.4064)
			(stroke
				(width 0.1524)
				(type default)
			)
			(layer "F.SilkS")
		)
		(fp_line
			(start 0.7874 -0.4064)
			(end 0.7874 0.4064)
			(stroke
				(width 0.1524)
				(type default)
			)
			(layer "F.SilkS")
		)
		(fp_line
			(start -0.67945 0.3048)
			(end -0.67945 -0.305054)
			(stroke
				(width 0.1)
				(type default)
			)
			(layer "F.Fab")
		)
		(fp_line
			(start -0.12065 0.3048)
			(end -0.67945 0.3048)
			(stroke
				(width 0.1)
				(type default)
			)
			(layer "F.Fab")
		)
		(fp_line
			(start 0.120396 0.3048)
			(end 0.120396 0.2794)
			(stroke
				(width 0.1)
				(type default)
			)
			(layer "F.Fab")
		)
		(fp_line
			(start 0.67945 0.3048)
			(end 0.120396 0.3048)
			(stroke
				(width 0.1)
				(type default)
			)
			(layer "F.Fab")
		)
		(fp_line
			(start -0.12065 0.2794)
			(end -0.12065 0.3048)
			(stroke
				(width 0.1)
				(type default)
			)
			(layer "F.Fab")
		)
		(fp_line
			(start 0.120396 0.2794)
			(end -0.12065 0.2794)
			(stroke
				(width 0.1)
				(type default)
			)
			(layer "F.Fab")
		)
		(fp_line
			(start -0.12065 -0.2794)
			(end 0.12065 -0.2794)
			(stroke
				(width 0.1)
				(type default)
			)
			(layer "F.Fab")
		)
		(fp_line
			(start 0.12065 -0.2794)
			(end 0.12065 -0.3048)
			(stroke
				(width 0.1)
				(type default)
			)
			(layer "F.Fab")
		)
		(fp_line
			(start 0.12065 -0.3048)
			(end 0.67945 -0.3048)
			(stroke
				(width 0.1)
				(type default)
			)
			(layer "F.Fab")
		)
		(fp_line
			(start 0.67945 -0.3048)
			(end 0.67945 0.3048)
			(stroke
				(width 0.1)
				(type default)
			)
			(layer "F.Fab")
		)
		(fp_line
			(start -0.67945 -0.305054)
			(end -0.12065 -0.305054)
			(stroke
				(width 0.1)
				(type default)
			)
			(layer "F.Fab")
		)
		(fp_line
			(start -0.12065 -0.305054)
			(end -0.12065 -0.2794)
			(stroke
				(width 0.1)
				(type default)
			)
			(layer "F.Fab")
		)
		(pad "1" smd circle
			(at -0.40005 0 270)
			(size 0 0)
			(layers "F.Cu" "F.Mask" "F.Paste")
			(net "P12V_E1S_0")
		)
		(pad "2" smd circle
			(at 0.40005 0 270)
			(size 0 0)
			(layers "F.Cu" "F.Mask" "F.Paste")
			(net "GND")
		)
	)
)
